(kicad_pcb
	(version 20241229)
	(generator "pcbnew")
	(generator_version "9.0")
	(general
		(thickness 1.711)
		(legacy_teardrops no)
	)
	(paper "A4")
	(title_block
		(title "Antmicro Baseboard for Jetson AGX Thor")
		(date "2026-02-18")
		(rev "1.1.0")
		(company "Antmicro Ltd")
		(comment 1 "www.antmicro.com")
		(comment 9 "footprints 504-508 of 1170")
	)
	(layers
		(0 "F.Cu" signal)
		(4 "In1.Cu" signal)
		(6 "In2.Cu" signal)
		(8 "In3.Cu" signal)
		(10 "In4.Cu" jumper)
		(12 "In5.Cu" signal)
		(14 "In6.Cu" signal)
		(16 "In7.Cu" signal)
		(18 "In8.Cu" signal)
		(2 "B.Cu" signal)
		(9 "F.Adhes" user "F.Adhesive")
		(11 "B.Adhes" user "B.Adhesive")
		(13 "F.Paste" user)
		(15 "B.Paste" user)
		(5 "F.SilkS" user "F.Silkscreen")
		(7 "B.SilkS" user "B.Silkscreen")
		(1 "F.Mask" user)
		(3 "B.Mask" user)
		(17 "Dwgs.User" user "User.Drawings")
		(19 "Cmts.User" user "User.Comments")
		(21 "Eco1.User" user "User.Eco1")
		(23 "Eco2.User" user "User.Eco2")
		(25 "Edge.Cuts" user)
		(27 "Margin" user)
		(31 "F.CrtYd" user "F.Courtyard")
		(29 "B.CrtYd" user "B.Courtyard")
		(35 "F.Fab" user)
		(33 "B.Fab" user)
	)
	(footprint "antmicro-footprints:C_0402_1005Metric"
		(layer "F.Cu")
		(at 219.404001 98.010001 180)
		(descr "Capacitor SMD 0402")
		(tags "capacitor SMD 0402")
		(property "Reference" "C110"
			(at -1.319999 1.420001 0)
			(layer "F.SilkS")
			(effects
				(font
					(size 0.7 0.7)
					(thickness 0.15)
				)
				(justify right top)
			)
		)
		(property "Value" "C_100n_0402"
			(at -1.022927 2.155213 0)
			(layer "F.Fab")
			(effects
				(font
					(size 0.7 0.7)
					(thickness 0.15)
				)
				(justify right top)
			)
		)
		(property "Datasheet" "https://www.murata.com/products/productdetail?partno=GRM155R61H104KE14%23"
			(at 0 0 0)
			(layer "F.Fab")
			(hide yes)
			(effects
				(font
					(size 1.27 1.27)
					(thickness 0.15)
				)
			)
		)
		(property "Description" "SMD Multilayer Ceramic Capacitor, 0.1 µF, 50 V, 0402 [1005 Metric], ± 10%, X5R, GRM Series"
			(at 0 0 0)
			(layer "F.Fab")
			(hide yes)
			(effects
				(font
					(size 1.27 1.27)
					(thickness 0.15)
				)
			)
		)
		(property "Manufacturer" "Murata"
			(at 0 0 180)
			(unlocked yes)
			(layer "F.Fab")
			(hide yes)
			(effects
				(font
					(size 1 1)
					(thickness 0.15)
				)
			)
		)
		(property "MPN" "GRM155R61H104KE14D"
			(at 0 0 180)
			(unlocked yes)
			(layer "F.Fab")
			(hide yes)
			(effects
				(font
					(size 1 1)
					(thickness 0.15)
				)
			)
		)
		(property "Val" "100n"
			(at 0 0 180)
			(unlocked yes)
			(layer "F.Fab")
			(hide yes)
			(effects
				(font
					(size 1 1)
					(thickness 0.15)
				)
			)
		)
		(property "License" "Apache-2.0"
			(at 0 0 180)
			(unlocked yes)
			(layer "F.Fab")
			(hide yes)
			(effects
				(font
					(size 1 1)
					(thickness 0.15)
				)
			)
		)
		(property "Author" "Antmicro"
			(at 0 0 180)
			(unlocked yes)
			(layer "F.Fab")
			(hide yes)
			(effects
				(font
					(size 1 1)
					(thickness 0.15)
				)
			)
		)
		(property "Voltage" "50V"
			(at 0 0 180)
			(unlocked yes)
			(layer "F.Fab")
			(hide yes)
			(effects
				(font
					(size 1 1)
					(thickness 0.15)
				)
			)
		)
		(property "Dielectric" "X5R"
			(at 0 0 180)
			(unlocked yes)
			(layer "F.Fab")
			(hide yes)
			(effects
				(font
					(size 1 1)
					(thickness 0.15)
				)
			)
		)
		(sheetname "/Recovery USB/")
		(sheetfile "recovery_usb.kicad_sch")
		(attr smd)
		(fp_rect
			(start -0.925 -0.47)
			(end 0.925 0.47)
			(stroke
				(width 0.05)
				(type default)
			)
			(fill no)
			(layer "F.CrtYd")
		)
		(fp_line
			(start 0.504 0.248)
			(end -0.494 0.248)
			(stroke
				(width 0.15)
				(type solid)
			)
			(layer "F.Fab")
		)
		(fp_line
			(start 0.504 -0.25)
			(end 0.504 0.248)
			(stroke
				(width 0.15)
				(type solid)
			)
			(layer "F.Fab")
		)
		(fp_line
			(start -0.494 0.248)
			(end -0.494 -0.25)
			(stroke
				(width 0.15)
				(type solid)
			)
			(layer "F.Fab")
		)
		(fp_line
			(start -0.494 -0.25)
			(end 0.504 -0.25)
			(stroke
				(width 0.15)
				(type solid)
			)
			(layer "F.Fab")
		)
		(fp_text user "Author: Antmicro"
			(at -0.939 3.399 0)
			(layer "F.Fab")
			(effects
				(font
					(size 0.7 0.7)
					(thickness 0.15)
				)
				(justify right top)
			)
		)
		(fp_text user "License: Apache-2.0"
			(at -0.939 5.799 0)
			(layer "F.Fab")
			(effects
				(font
					(size 0.7 0.7)
					(thickness 0.15)
				)
				(justify right top)
			)
		)
		(fp_text user "${REFERENCE}"
			(at -0.939 4.599 0)
			(layer "F.Fab")
			(effects
				(font
					(size 0.7 0.7)
					(thickness 0.15)
				)
				(justify right top)
			)
		)
		(pad "1" smd roundrect
			(at -0.48 0 180)
			(size 0.59 0.64)
			(layers "F.Cu" "F.Mask" "F.Paste")
			(roundrect_rratio 0.25)
			(net 270 "/Recovery USB/USBC2_CONN_TX2_P")
			(pintype "passive")
		)
		(pad "2" smd roundrect
			(at 0.48 0 180)
			(size 0.59 0.64)
			(layers "F.Cu" "F.Mask" "F.Paste")
			(roundrect_rratio 0.25)
			(net 260 "/Recovery USB/USBC2_TX2_P")
			(pintype "passive")
		)
	)
	(footprint "antmicro-footprints:R_0402_1005Metric"
		(layer "F.Cu")
		(at 144.484391 125.92 -90)
		(descr "Resistor SMD 0402")
		(tags "resistor SMD 0402")
		(property "Reference" "R318"
			(at -4.54 0.422 90)
			(layer "F.SilkS")
			(effects
				(font
					(size 0.7 0.7)
					(thickness 0.15)
				)
				(justify right top)
			)
		)
		(property "Value" "R_15k_0402"
			(at -1.011843 1.772047 90)
			(layer "F.Fab")
			(effects
				(font
					(size 0.7 0.7)
					(thickness 0.15)
				)
				(justify right top)
			)
		)
		(property "Datasheet" "https://www.bourns.com/docs/product-datasheets/cr.pdf"
			(at 0 0 90)
			(layer "F.Fab")
			(hide yes)
			(effects
				(font
					(size 1.27 1.27)
					(thickness 0.15)
				)
			)
		)
		(property "Description" "SMD Chip Resistor, 15 kohm, ± 1%, 62.5 mW, 0402 [1005 Metric], Thick Film, General Purpose"
			(at 0 0 90)
			(layer "F.Fab")
			(hide yes)
			(effects
				(font
					(size 1.27 1.27)
					(thickness 0.15)
				)
			)
		)
		(property "MPN" "CR0402-FX-1502GLF"
			(at 0 0 270)
			(unlocked yes)
			(layer "F.Fab")
			(hide yes)
			(effects
				(font
					(size 1 1)
					(thickness 0.15)
				)
			)
		)
		(property "Manufacturer" "Bourns"
			(at 0 0 270)
			(unlocked yes)
			(layer "F.Fab")
			(hide yes)
			(effects
				(font
					(size 1 1)
					(thickness 0.15)
				)
			)
		)
		(property "License" "Apache-2.0"
			(at 0 0 270)
			(unlocked yes)
			(layer "F.Fab")
			(hide yes)
			(effects
				(font
					(size 1 1)
					(thickness 0.15)
				)
			)
		)
		(property "Author" "Antmicro"
			(at 0 0 270)
			(unlocked yes)
			(layer "F.Fab")
			(hide yes)
			(effects
				(font
					(size 1 1)
					(thickness 0.15)
				)
			)
		)
		(property "Val" "15k"
			(at 0 0 270)
			(unlocked yes)
			(layer "F.Fab")
			(hide yes)
			(effects
				(font
					(size 1 1)
					(thickness 0.15)
				)
			)
		)
		(property "Tolerance" "1%"
			(at 0 0 270)
			(unlocked yes)
			(layer "F.Fab")
			(hide yes)
			(effects
				(font
					(size 1 1)
					(thickness 0.15)
				)
			)
		)
		(component_classes
			(class "DCDC_1V8")
		)
		(sheetname "/DCDC/")
		(sheetfile "dcdc.kicad_sch")
		(attr smd)
		(fp_rect
			(start -0.925 -0.47)
			(end 0.925 0.47)
			(stroke
				(width 0.05)
				(type default)
			)
			(fill no)
			(layer "F.CrtYd")
		)
		(fp_rect
			(start -0.5 -0.25)
			(end 0.5 0.25)
			(stroke
				(width 0.15)
				(type solid)
			)
			(fill no)
			(layer "F.Fab")
		)
		(fp_text user "${REFERENCE}"
			(at -0.95 3.168 90)
			(layer "F.Fab")
			(effects
				(font
					(size 0.7 0.7)
					(thickness 0.15)
				)
				(justify right top)
			)
		)
		(fp_text user "Author: Antmicro"
			(at -0.95 4.169 90)
			(layer "F.Fab")
			(effects
				(font
					(size 0.7 0.7)
					(thickness 0.15)
				)
				(justify right top)
			)
		)
		(fp_text user "License: Apache-2.0"
			(at -0.95 5.169 90)
			(layer "F.Fab")
			(effects
				(font
					(size 0.7 0.7)
					(thickness 0.15)
				)
				(justify right top)
			)
		)
		(pad "1" smd roundrect
			(at -0.48 0 270)
			(size 0.59 0.64)
			(layers "F.Cu" "F.Mask" "F.Paste")
			(roundrect_rratio 0.25)
			(net 1 "GND")
			(pintype "passive")
		)
		(pad "2" smd roundrect
			(at 0.48 0 270)
			(size 0.59 0.64)
			(layers "F.Cu" "F.Mask" "F.Paste")
			(roundrect_rratio 0.25)
			(net 1222 "/DCDC/1V8_FB")
			(pintype "passive")
		)
	)
	(footprint "antmicro-footprints:C_0402_1005Metric"
		(layer "F.Cu")
		(at 89.1 95.9)
		(descr "Capacitor SMD 0402")
		(tags "capacitor SMD 0402")
		(property "Reference" "C340"
			(at -3.82 0.45 0)
			(layer "F.SilkS")
			(effects
				(font
					(size 0.7 0.7)
					(thickness 0.15)
				)
				(justify left bottom)
			)
		)
		(property "Value" "C_100n_0402"
			(at -1.022927 2.155213 0)
			(layer "F.Fab")
			(effects
				(font
					(size 0.7 0.7)
					(thickness 0.15)
				)
				(justify left bottom)
			)
		)
		(property "Datasheet" "https://www.murata.com/products/productdetail?partno=GRM155R61H104KE14%23"
			(at 0 0 0)
			(layer "F.Fab")
			(hide yes)
			(effects
				(font
					(size 1.27 1.27)
					(thickness 0.15)
				)
			)
		)
		(property "Description" "SMD Multilayer Ceramic Capacitor, 0.1 µF, 50 V, 0402 [1005 Metric], ± 10%, X5R, GRM Series"
			(at 0 0 0)
			(layer "F.Fab")
			(hide yes)
			(effects
				(font
					(size 1.27 1.27)
					(thickness 0.15)
				)
			)
		)
		(property "Manufacturer" "Murata"
			(at 0 0 0)
			(unlocked yes)
			(layer "F.Fab")
			(hide yes)
			(effects
				(font
					(size 1 1)
					(thickness 0.15)
				)
			)
		)
		(property "MPN" "GRM155R61H104KE14D"
			(at 0 0 0)
			(unlocked yes)
			(layer "F.Fab")
			(hide yes)
			(effects
				(font
					(size 1 1)
					(thickness 0.15)
				)
			)
		)
		(property "Val" "100n"
			(at 0 0 0)
			(unlocked yes)
			(layer "F.Fab")
			(hide yes)
			(effects
				(font
					(size 1 1)
					(thickness 0.15)
				)
			)
		)
		(property "License" "Apache-2.0"
			(at 0 0 0)
			(unlocked yes)
			(layer "F.Fab")
			(hide yes)
			(effects
				(font
					(size 1 1)
					(thickness 0.15)
				)
			)
		)
		(property "Author" "Antmicro"
			(at 0 0 0)
			(unlocked yes)
			(layer "F.Fab")
			(hide yes)
			(effects
				(font
					(size 1 1)
					(thickness 0.15)
				)
			)
		)
		(property "Voltage" "50V"
			(at 0 0 0)
			(unlocked yes)
			(layer "F.Fab")
			(hide yes)
			(effects
				(font
					(size 1 1)
					(thickness 0.15)
				)
			)
		)
		(property "Dielectric" "X5R"
			(at 0 0 0)
			(unlocked yes)
			(layer "F.Fab")
			(hide yes)
			(effects
				(font
					(size 1 1)
					(thickness 0.15)
				)
			)
		)
		(sheetname "/SoM_IO2/")
		(sheetfile "som_io2.kicad_sch")
		(attr smd)
		(fp_rect
			(start -0.925 -0.47)
			(end 0.925 0.47)
			(stroke
				(width 0.05)
				(type default)
			)
			(fill no)
			(layer "F.CrtYd")
		)
		(fp_line
			(start -0.494 -0.25)
			(end 0.504 -0.25)
			(stroke
				(width 0.15)
				(type solid)
			)
			(layer "F.Fab")
		)
		(fp_line
			(start -0.494 0.248)
			(end -0.494 -0.25)
			(stroke
				(width 0.15)
				(type solid)
			)
			(layer "F.Fab")
		)
		(fp_line
			(start 0.504 -0.25)
			(end 0.504 0.248)
			(stroke
				(width 0.15)
				(type solid)
			)
			(layer "F.Fab")
		)
		(fp_line
			(start 0.504 0.248)
			(end -0.494 0.248)
			(stroke
				(width 0.15)
				(type solid)
			)
			(layer "F.Fab")
		)
		(fp_text user "${REFERENCE}"
			(at -0.939 4.599 0)
			(layer "F.Fab")
			(effects
				(font
					(size 0.7 0.7)
					(thickness 0.15)
				)
				(justify left bottom)
			)
		)
		(fp_text user "License: Apache-2.0"
			(at -0.939 5.799 0)
			(layer "F.Fab")
			(effects
				(font
					(size 0.7 0.7)
					(thickness 0.15)
				)
				(justify left bottom)
			)
		)
		(fp_text user "Author: Antmicro"
			(at -0.939 3.399 0)
			(layer "F.Fab")
			(effects
				(font
					(size 0.7 0.7)
					(thickness 0.15)
				)
				(justify left bottom)
			)
		)
		(pad "1" smd roundrect
			(at -0.48 0)
			(size 0.59 0.64)
			(layers "F.Cu" "F.Mask" "F.Paste")
			(roundrect_rratio 0.25)
			(net 742 "/Expansion connector/DP2.TX2-")
			(pintype "passive")
		)
		(pad "2" smd roundrect
			(at 0.48 0)
			(size 0.59 0.64)
			(layers "F.Cu" "F.Mask" "F.Paste")
			(roundrect_rratio 0.25)
			(net 1260 "/SoM_IO2/DP2.TX2_C-")
			(pintype "passive")
		)
	)
	(footprint "antmicro-footprints:C_0402_1005Metric"
		(layer "F.Cu")
		(at 207.88 134.8 90)
		(descr "Capacitor SMD 0402")
		(tags "capacitor SMD 0402")
		(property "Reference" "C254"
			(at -1.6 13.92 90)
			(layer "F.SilkS")
			(effects
				(font
					(size 0.7 0.7)
					(thickness 0.15)
				)
				(justify left bottom)
			)
		)
		(property "Value" "C_100n_0402"
			(at -1.022927 2.155213 90)
			(layer "F.Fab")
			(effects
				(font
					(size 0.7 0.7)
					(thickness 0.15)
				)
				(justify left bottom)
			)
		)
		(property "Datasheet" "https://www.murata.com/products/productdetail?partno=GRM155R61H104KE14%23"
			(at 0 0 90)
			(layer "F.Fab")
			(hide yes)
			(effects
				(font
					(size 1.27 1.27)
					(thickness 0.15)
				)
			)
		)
		(property "Description" "SMD Multilayer Ceramic Capacitor, 0.1 µF, 50 V, 0402 [1005 Metric], ± 10%, X5R, GRM Series"
			(at 0 0 90)
			(layer "F.Fab")
			(hide yes)
			(effects
				(font
					(size 1.27 1.27)
					(thickness 0.15)
				)
			)
		)
		(property "Manufacturer" "Murata"
			(at 0 0 90)
			(unlocked yes)
			(layer "F.Fab")
			(hide yes)
			(effects
				(font
					(size 1 1)
					(thickness 0.15)
				)
			)
		)
		(property "MPN" "GRM155R61H104KE14D"
			(at 0 0 90)
			(unlocked yes)
			(layer "F.Fab")
			(hide yes)
			(effects
				(font
					(size 1 1)
					(thickness 0.15)
				)
			)
		)
		(property "Val" "100n"
			(at 0 0 90)
			(unlocked yes)
			(layer "F.Fab")
			(hide yes)
			(effects
				(font
					(size 1 1)
					(thickness 0.15)
				)
			)
		)
		(property "License" "Apache-2.0"
			(at 0 0 90)
			(unlocked yes)
			(layer "F.Fab")
			(hide yes)
			(effects
				(font
					(size 1 1)
					(thickness 0.15)
				)
			)
		)
		(property "Author" "Antmicro"
			(at 0 0 90)
			(unlocked yes)
			(layer "F.Fab")
			(hide yes)
			(effects
				(font
					(size 1 1)
					(thickness 0.15)
				)
			)
		)
		(property "Voltage" "50V"
			(at 0 0 90)
			(unlocked yes)
			(layer "F.Fab")
			(hide yes)
			(effects
				(font
					(size 1 1)
					(thickness 0.15)
				)
			)
		)
		(property "Dielectric" "X5R"
			(at 0 0 90)
			(unlocked yes)
			(layer "F.Fab")
			(hide yes)
			(effects
				(font
					(size 1 1)
					(thickness 0.15)
				)
			)
		)
		(sheetname "/USB Hub/")
		(sheetfile "usb_hub.kicad_sch")
		(attr smd)
		(fp_rect
			(start -0.925 -0.47)
			(end 0.925 0.47)
			(stroke
				(width 0.05)
				(type default)
			)
			(fill no)
			(layer "F.CrtYd")
		)
		(fp_line
			(start 0.504 -0.25)
			(end 0.504 0.248)
			(stroke
				(width 0.15)
				(type solid)
			)
			(layer "F.Fab")
		)
		(fp_line
			(start -0.494 -0.25)
			(end 0.504 -0.25)
			(stroke
				(width 0.15)
				(type solid)
			)
			(layer "F.Fab")
		)
		(fp_line
			(start 0.504 0.248)
			(end -0.494 0.248)
			(stroke
				(width 0.15)
				(type solid)
			)
			(layer "F.Fab")
		)
		(fp_line
			(start -0.494 0.248)
			(end -0.494 -0.25)
			(stroke
				(width 0.15)
				(type solid)
			)
			(layer "F.Fab")
		)
		(fp_text user "License: Apache-2.0"
			(at -0.939 5.799 90)
			(layer "F.Fab")
			(effects
				(font
					(size 0.7 0.7)
					(thickness 0.15)
				)
				(justify left bottom)
			)
		)
		(fp_text user "Author: Antmicro"
			(at -0.939 3.399 90)
			(layer "F.Fab")
			(effects
				(font
					(size 0.7 0.7)
					(thickness 0.15)
				)
				(justify left bottom)
			)
		)
		(fp_text user "${REFERENCE}"
			(at -0.939 4.599 90)
			(layer "F.Fab")
			(effects
				(font
					(size 0.7 0.7)
					(thickness 0.15)
				)
				(justify left bottom)
			)
		)
		(pad "1" smd roundrect
			(at -0.48 0 90)
			(size 0.59 0.64)
			(layers "F.Cu" "F.Mask" "F.Paste")
			(roundrect_rratio 0.25)
			(net 684 "/SoM_IO2/USBSS2.TX+")
			(pintype "passive")
		)
		(pad "2" smd roundrect
			(at 0.48 0 90)
			(size 0.59 0.64)
			(layers "F.Cu" "F.Mask" "F.Paste")
			(roundrect_rratio 0.25)
			(net 1133 "/USB Hub/USBSS_RX_P")
			(pintype "passive")
		)
	)
	(footprint "antmicro-footprints:C_0805_2012Metric"
		(layer "F.Cu")
		(at 167.72 79.81 90)
		(descr "Capacitor SMD 0805")
		(tags "capacitor SMD 0805")
		(property "Reference" "C284"
			(at -4.7 0.29 90)
			(layer "F.SilkS")
			(effects
				(font
					(size 0.7 0.7)
					(thickness 0.15)
				)
				(justify left bottom)
			)
		)
		(property "Value" "C_22u_25V_0805"
			(at -2.055717 1.963152 90)
			(layer "F.Fab")
			(effects
				(font
					(size 0.7 0.7)
					(thickness 0.15)
				)
				(justify left bottom)
			)
		)
		(property "Datasheet" "https://product.samsungsem.com/mlcc/CL21A226MAYNNN.do"
			(at 0 0 90)
			(layer "F.Fab")
			(hide yes)
			(effects
				(font
					(size 1.27 1.27)
					(thickness 0.15)
				)
			)
		)
		(property "Description" "SMT Multilayer Ceramic Capacitor, 22uF, +/-20%, 25V, X5R, 0805 [2012 Metric]"
			(at 0 0 90)
			(layer "F.Fab")
			(hide yes)
			(effects
				(font
					(size 1.27 1.27)
					(thickness 0.15)
				)
			)
		)
		(property "MPN" "CL21A226MAYNNNE"
			(at 0 0 90)
			(unlocked yes)
			(layer "F.Fab")
			(hide yes)
			(effects
				(font
					(size 1 1)
					(thickness 0.15)
				)
			)
		)
		(property "Manufacturer" "Samsung Electro-Mechanics"
			(at 0 0 90)
			(unlocked yes)
			(layer "F.Fab")
			(hide yes)
			(effects
				(font
					(size 1 1)
					(thickness 0.15)
				)
			)
		)
		(property "License" "Apache-2.0"
			(at 0 0 90)
			(unlocked yes)
			(layer "F.Fab")
			(hide yes)
			(effects
				(font
					(size 1 1)
					(thickness 0.15)
				)
			)
		)
		(property "Author" "Antmicro"
			(at 0 0 90)
			(unlocked yes)
			(layer "F.Fab")
			(hide yes)
			(effects
				(font
					(size 1 1)
					(thickness 0.15)
				)
			)
		)
		(property "Val" "22u"
			(at 0 0 90)
			(unlocked yes)
			(layer "F.Fab")
			(hide yes)
			(effects
				(font
					(size 1 1)
					(thickness 0.15)
				)
			)
		)
		(property "Voltage" "25V"
			(at 0 0 90)
			(unlocked yes)
			(layer "F.Fab")
			(hide yes)
			(effects
				(font
					(size 1 1)
					(thickness 0.15)
				)
			)
		)
		(property "Dielectric" "X5R"
			(at 0 0 90)
			(unlocked yes)
			(layer "F.Fab")
			(hide yes)
			(effects
				(font
					(size 1 1)
					(thickness 0.15)
				)
			)
		)
		(property "Public" "False"
			(at 0 0 90)
			(unlocked yes)
			(layer "F.Fab")
			(hide yes)
			(effects
				(font
					(size 1 1)
					(thickness 0.15)
				)
			)
		)
		(component_classes
			(class "DCDC_20V")
		)
		(sheetname "/DCDC/")
		(sheetfile "dcdc.kicad_sch")
		(attr smd)
		(fp_line
			(start -0.3 -0.7)
			(end 0.3 -0.7)
			(stroke
				(width 0.15)
				(type solid)
			)
			(layer "F.SilkS")
		)
		(fp_line
			(start -0.3 0.7)
			(end 0.3 0.7)
			(stroke
				(width 0.15)
				(type solid)
			)
			(layer "F.SilkS")
		)
		(fp_rect
			(start 1.95 -0.9)
			(end -1.95 0.9)
			(stroke
				(width 0.05)
				(type default)
			)
			(fill no)
			(layer "F.CrtYd")
		)
		(fp_rect
			(start -0.95 -0.675)
			(end 0.95 0.675)
			(stroke
				(width 0.15)
				(type solid)
			)
			(fill no)
			(layer "F.Fab")
		)
		(fp_text user "License: Apache-2.0"
			(at -1.9 4.947 90)
			(layer "F.Fab")
			(effects
				(font
					(size 0.7 0.7)
					(thickness 0.15)
				)
				(justify left bottom)
			)
		)
		(fp_text user "${REFERENCE}"
			(at -1.9 3.947 90)
			(layer "F.Fab")
			(effects
				(font
					(size 0.7 0.7)
					(thickness 0.15)
				)
				(justify left bottom)
			)
		)
		(fp_text user "Author: Antmicro"
			(at -1.9 5.947 90)
			(layer "F.Fab")
			(effects
				(font
					(size 0.7 0.7)
					(thickness 0.15)
				)
				(justify left bottom)
			)
		)
		(pad "1" smd roundrect
			(at -1.1 0 90)
			(size 1.2 1.3)
			(layers "F.Cu" "F.Mask" "F.Paste")
			(roundrect_rratio 0.25)
			(net 1 "GND")
			(pintype "passive")
		)
		(pad "2" smd roundrect
			(at 1.1 0 90)
			(size 1.2 1.3)
			(layers "F.Cu" "F.Mask" "F.Paste")
			(roundrect_rratio 0.25)
			(net 1105 "/DCDC/20V_OUT")
			(pintype "passive")
		)
	)
)
